(kicad_pcb
	(version 20260206)
	(generator "pcbnew")
	(generator_version "10.0")
	(general
		(thickness 1.6)
		(legacy_teardrops no)
	)
	(paper "A4")
	(title_block
		(title "03242023_DA0F0TMBIJ0_F0T_Motherboard_J_brd_V01_OCP.brd")
		(comment 1 "Grand Teton / footprints 1994-2000 of 6105")
	)
	(layers
		(0 "F.Cu" signal "TOP")
		(4 "In1.Cu" signal "GND")
		(6 "In2.Cu" signal "IN1")
		(8 "In3.Cu" signal "GND1")
		(10 "In4.Cu" signal "IN2")
		(12 "In5.Cu" signal "GND2")
		(14 "In6.Cu" signal "IN3")
		(16 "In7.Cu" signal "GND3")
		(18 "In8.Cu" signal "VCC")
		(20 "In9.Cu" signal "VCC1")
		(22 "In10.Cu" signal "GND4")
		(24 "In11.Cu" signal "IN4")
		(26 "In12.Cu" signal "GND5")
		(28 "In13.Cu" signal "IN5")
		(30 "In14.Cu" signal "GND6")
		(32 "In15.Cu" signal "IN6")
		(34 "In16.Cu" signal "GND7")
		(2 "B.Cu" signal "BOTTOM")
		(9 "F.Adhes" user "F.Adhesive")
		(11 "B.Adhes" user "B.Adhesive")
		(13 "F.Paste" user "Package Geometry/Pastemask Top")
		(15 "B.Paste" user "Package Geometry/Pastemask Bottom")
		(5 "F.SilkS" user "Ref Des/Silkscreen Top")
		(7 "B.SilkS" user "Ref Des/Silkscreen Bottom")
		(1 "F.Mask" user "Board Geometry/Soldermask Top")
		(3 "B.Mask" user "Board Geometry/Soldermask Bottom")
		(17 "Dwgs.User" user "User.Drawings")
		(19 "Cmts.User" user "User.Comments")
		(21 "Eco1.User" user "User.Eco1")
		(23 "Eco2.User" user "User.Eco2")
		(25 "Edge.Cuts" user "Board Geometry/Outline")
		(27 "Margin" user)
		(31 "F.CrtYd" user "Package Geometry/Place Bound Top")
		(29 "B.CrtYd" user "Package Geometry/Place Bound Bottom")
		(35 "F.Fab" user "Ref Des/Assembly Top")
		(33 "B.Fab" user "Ref Des/Assembly Bottom")
	)
	(footprint ""
		(layer "F.Cu")
		(at 173.5836 -366.33023)
		(property "Reference" "PC1658"
			(at 0 0 0)
			(layer "F.SilkS")
			(hide yes)
			(effects
				(font
					(size 1.27 1.27)
				)
			)
		)
		(property "Value" ""
			(at 0 0 0)
			(layer "F.Fab")
			(effects
				(font
					(size 1.27 1.27)
				)
			)
		)
		(duplicate_pad_numbers_are_jumpers no)
		(fp_line
			(start -0.7874 -0.4064)
			(end 0.7874 -0.4064)
			(stroke
				(width 0.1524)
				(type default)
			)
			(layer "F.SilkS")
		)
		(fp_line
			(start -0.7874 0.4064)
			(end -0.7874 -0.4064)
			(stroke
				(width 0.1524)
				(type default)
			)
			(layer "F.SilkS")
		)
		(fp_line
			(start 0.7874 -0.4064)
			(end 0.7874 0.4064)
			(stroke
				(width 0.1524)
				(type default)
			)
			(layer "F.SilkS")
		)
		(fp_line
			(start 0.7874 0.4064)
			(end -0.7874 0.4064)
			(stroke
				(width 0.1524)
				(type default)
			)
			(layer "F.SilkS")
		)
		(fp_line
			(start -0.67945 -0.305054)
			(end -0.12065 -0.305054)
			(stroke
				(width 0.1)
				(type default)
			)
			(layer "F.Fab")
		)
		(fp_line
			(start -0.67945 0.3048)
			(end -0.67945 -0.305054)
			(stroke
				(width 0.1)
				(type default)
			)
			(layer "F.Fab")
		)
		(fp_line
			(start -0.12065 -0.305054)
			(end -0.12065 -0.2794)
			(stroke
				(width 0.1)
				(type default)
			)
			(layer "F.Fab")
		)
		(fp_line
			(start -0.12065 -0.2794)
			(end 0.12065 -0.2794)
			(stroke
				(width 0.1)
				(type default)
			)
			(layer "F.Fab")
		)
		(fp_line
			(start -0.12065 0.2794)
			(end -0.12065 0.3048)
			(stroke
				(width 0.1)
				(type default)
			)
			(layer "F.Fab")
		)
		(fp_line
			(start -0.12065 0.3048)
			(end -0.67945 0.3048)
			(stroke
				(width 0.1)
				(type default)
			)
			(layer "F.Fab")
		)
		(fp_line
			(start 0.120396 0.2794)
			(end -0.12065 0.2794)
			(stroke
				(width 0.1)
				(type default)
			)
			(layer "F.Fab")
		)
		(fp_line
			(start 0.120396 0.3048)
			(end 0.120396 0.2794)
			(stroke
				(width 0.1)
				(type default)
			)
			(layer "F.Fab")
		)
		(fp_line
			(start 0.12065 -0.3048)
			(end 0.67945 -0.3048)
			(stroke
				(width 0.1)
				(type default)
			)
			(layer "F.Fab")
		)
		(fp_line
			(start 0.12065 -0.2794)
			(end 0.12065 -0.3048)
			(stroke
				(width 0.1)
				(type default)
			)
			(layer "F.Fab")
		)
		(fp_line
			(start 0.67945 -0.3048)
			(end 0.67945 0.3048)
			(stroke
				(width 0.1)
				(type default)
			)
			(layer "F.Fab")
		)
		(fp_line
			(start 0.67945 0.3048)
			(end 0.120396 0.3048)
			(stroke
				(width 0.1)
				(type default)
			)
			(layer "F.Fab")
		)
		(pad "1" smd circle
			(at -0.40005 0)
			(size 0 0)
			(layers "F.Cu" "F.Mask" "F.Paste")
			(net "P12V_AUX")
		)
		(pad "2" smd circle
			(at 0.40005 0)
			(size 0 0)
			(layers "F.Cu" "F.Mask" "F.Paste")
			(net "GND")
		)
	)
	(footprint ""
		(layer "F.Cu")
		(at 220.345 -49.911 180)
		(property "Reference" "C2378"
			(at 0 0 180)
			(layer "F.SilkS")
			(hide yes)
			(effects
				(font
					(size 1.27 1.27)
				)
			)
		)
		(property "Value" ""
			(at 0 0 180)
			(layer "F.Fab")
			(effects
				(font
					(size 1.27 1.27)
				)
			)
		)
		(duplicate_pad_numbers_are_jumpers no)
		(fp_line
			(start 0.7874 0.4064)
			(end -0.7874 0.4064)
			(stroke
				(width 0.1524)
				(type default)
			)
			(layer "F.SilkS")
		)
		(fp_line
			(start 0.7874 -0.4064)
			(end 0.7874 0.4064)
			(stroke
				(width 0.1524)
				(type default)
			)
			(layer "F.SilkS")
		)
		(fp_line
			(start -0.7874 0.4064)
			(end -0.7874 -0.4064)
			(stroke
				(width 0.1524)
				(type default)
			)
			(layer "F.SilkS")
		)
		(fp_line
			(start -0.7874 -0.4064)
			(end 0.7874 -0.4064)
			(stroke
				(width 0.1524)
				(type default)
			)
			(layer "F.SilkS")
		)
		(fp_line
			(start 0.67945 0.3048)
			(end 0.120396 0.3048)
			(stroke
				(width 0.1)
				(type default)
			)
			(layer "F.Fab")
		)
		(fp_line
			(start 0.67945 -0.3048)
			(end 0.67945 0.3048)
			(stroke
				(width 0.1)
				(type default)
			)
			(layer "F.Fab")
		)
		(fp_line
			(start 0.12065 -0.2794)
			(end 0.12065 -0.3048)
			(stroke
				(width 0.1)
				(type default)
			)
			(layer "F.Fab")
		)
		(fp_line
			(start 0.12065 -0.3048)
			(end 0.67945 -0.3048)
			(stroke
				(width 0.1)
				(type default)
			)
			(layer "F.Fab")
		)
		(fp_line
			(start 0.120396 0.3048)
			(end 0.120396 0.2794)
			(stroke
				(width 0.1)
				(type default)
			)
			(layer "F.Fab")
		)
		(fp_line
			(start 0.120396 0.2794)
			(end -0.12065 0.2794)
			(stroke
				(width 0.1)
				(type default)
			)
			(layer "F.Fab")
		)
		(fp_line
			(start -0.12065 0.3048)
			(end -0.67945 0.3048)
			(stroke
				(width 0.1)
				(type default)
			)
			(layer "F.Fab")
		)
		(fp_line
			(start -0.12065 0.2794)
			(end -0.12065 0.3048)
			(stroke
				(width 0.1)
				(type default)
			)
			(layer "F.Fab")
		)
		(fp_line
			(start -0.12065 -0.2794)
			(end 0.12065 -0.2794)
			(stroke
				(width 0.1)
				(type default)
			)
			(layer "F.Fab")
		)
		(fp_line
			(start -0.12065 -0.305054)
			(end -0.12065 -0.2794)
			(stroke
				(width 0.1)
				(type default)
			)
			(layer "F.Fab")
		)
		(fp_line
			(start -0.67945 0.3048)
			(end -0.67945 -0.305054)
			(stroke
				(width 0.1)
				(type default)
			)
			(layer "F.Fab")
		)
		(fp_line
			(start -0.67945 -0.305054)
			(end -0.12065 -0.305054)
			(stroke
				(width 0.1)
				(type default)
			)
			(layer "F.Fab")
		)
		(pad "1" smd circle
			(at -0.40005 0 180)
			(size 0 0)
			(layers "F.Cu" "F.Mask" "F.Paste")
			(net "P3V3_E1S_0")
		)
		(pad "2" smd circle
			(at 0.40005 0 180)
			(size 0 0)
			(layers "F.Cu" "F.Mask" "F.Paste")
			(net "GND")
		)
	)
	(footprint ""
		(layer "F.Cu")
		(at 375.37517 -402.371052 -90)
		(property "Reference" "C936"
			(at 0 0 270)
			(layer "F.SilkS")
			(hide yes)
			(effects
				(font
					(size 1.27 1.27)
				)
			)
		)
		(property "Value" ""
			(at 0 0 270)
			(layer "F.Fab")
			(effects
				(font
					(size 1.27 1.27)
				)
			)
		)
		(duplicate_pad_numbers_are_jumpers no)
		(fp_line
			(start -0.299974 0.150114)
			(end -0.299974 -0.150114)
			(stroke
				(width 0.1)
				(type default)
			)
			(layer "F.Fab")
		)
		(fp_line
			(start 0.299974 0.150114)
			(end -0.299974 0.150114)
			(stroke
				(width 0.1)
				(type default)
			)
			(layer "F.Fab")
		)
		(fp_line
			(start -0.299974 -0.150114)
			(end 0.299974 -0.150114)
			(stroke
				(width 0.1)
				(type default)
			)
			(layer "F.Fab")
		)
		(fp_line
			(start 0.299974 -0.150114)
			(end 0.299974 0.150114)
			(stroke
				(width 0.1)
				(type default)
			)
			(layer "F.Fab")
		)
		(pad "1" smd rect
			(at -0.2667 0 270)
			(size 0.3048 0.381)
			(layers "F.Cu" "F.Mask" "F.Paste")
			(net "P5E_CPU0_PE2_TX_C_DN<14>")
		)
		(pad "2" smd rect
			(at 0.2667 0 270)
			(size 0.3048 0.381)
			(layers "F.Cu" "F.Mask" "F.Paste")
			(net "P5E_CPU0_PE2_TX_DN<14>")
		)
	)
	(footprint ""
		(layer "F.Cu")
		(at 394.141198 -161.07791 180)
		(property "Reference" "R969"
			(at 0 0 180)
			(layer "F.SilkS")
			(hide yes)
			(effects
				(font
					(size 1.27 1.27)
				)
			)
		)
		(property "Value" ""
			(at 0 0 180)
			(layer "F.Fab")
			(effects
				(font
					(size 1.27 1.27)
				)
			)
		)
		(duplicate_pad_numbers_are_jumpers no)
		(fp_line
			(start 0.7874 0.4064)
			(end -0.7874 0.4064)
			(stroke
				(width 0.1524)
				(type default)
			)
			(layer "F.SilkS")
		)
		(fp_line
			(start 0.7874 -0.4064)
			(end 0.7874 0.4064)
			(stroke
				(width 0.1524)
				(type default)
			)
			(layer "F.SilkS")
		)
		(fp_line
			(start -0.7874 0.4064)
			(end -0.7874 -0.4064)
			(stroke
				(width 0.1524)
				(type default)
			)
			(layer "F.SilkS")
		)
		(fp_line
			(start -0.7874 -0.4064)
			(end 0.7874 -0.4064)
			(stroke
				(width 0.1524)
				(type default)
			)
			(layer "F.SilkS")
		)
		(fp_line
			(start 0.67945 0.3048)
			(end 0.120396 0.3048)
			(stroke
				(width 0.1)
				(type default)
			)
			(layer "F.Fab")
		)
		(fp_line
			(start 0.67945 -0.3048)
			(end 0.67945 0.3048)
			(stroke
				(width 0.1)
				(type default)
			)
			(layer "F.Fab")
		)
		(fp_line
			(start 0.12065 -0.2794)
			(end 0.12065 -0.3048)
			(stroke
				(width 0.1)
				(type default)
			)
			(layer "F.Fab")
		)
		(fp_line
			(start 0.12065 -0.3048)
			(end 0.67945 -0.3048)
			(stroke
				(width 0.1)
				(type default)
			)
			(layer "F.Fab")
		)
		(fp_line
			(start 0.120396 0.3048)
			(end 0.120396 0.2794)
			(stroke
				(width 0.1)
				(type default)
			)
			(layer "F.Fab")
		)
		(fp_line
			(start 0.120396 0.2794)
			(end -0.12065 0.2794)
			(stroke
				(width 0.1)
				(type default)
			)
			(layer "F.Fab")
		)
		(fp_line
			(start -0.12065 0.3048)
			(end -0.67945 0.3048)
			(stroke
				(width 0.1)
				(type default)
			)
			(layer "F.Fab")
		)
		(fp_line
			(start -0.12065 0.2794)
			(end -0.12065 0.3048)
			(stroke
				(width 0.1)
				(type default)
			)
			(layer "F.Fab")
		)
		(fp_line
			(start -0.12065 -0.2794)
			(end 0.12065 -0.2794)
			(stroke
				(width 0.1)
				(type default)
			)
			(layer "F.Fab")
		)
		(fp_line
			(start -0.12065 -0.305054)
			(end -0.12065 -0.2794)
			(stroke
				(width 0.1)
				(type default)
			)
			(layer "F.Fab")
		)
		(fp_line
			(start -0.67945 0.3048)
			(end -0.67945 -0.305054)
			(stroke
				(width 0.1)
				(type default)
			)
			(layer "F.Fab")
		)
		(fp_line
			(start -0.67945 -0.305054)
			(end -0.12065 -0.305054)
			(stroke
				(width 0.1)
				(type default)
			)
			(layer "F.Fab")
		)
		(pad "1" smd circle
			(at -0.40005 0 180)
			(size 0 0)
			(layers "F.Cu" "F.Mask" "F.Paste")
			(net "PVNN_TERM_CPU0")
		)
		(pad "2" smd circle
			(at 0.40005 0 180)
			(size 0 0)
			(layers "F.Cu" "F.Mask" "F.Paste")
			(net "SMB_S3M_CPU0_R_SCL")
		)
	)
	(footprint ""
		(layer "F.Cu")
		(at 355.227128 -260.364986 -90)
		(property "Reference" "C413"
			(at 0 0 270)
			(layer "F.SilkS")
			(hide yes)
			(effects
				(font
					(size 1.27 1.27)
				)
			)
		)
		(property "Value" ""
			(at 0 0 270)
			(layer "F.Fab")
			(effects
				(font
					(size 1.27 1.27)
				)
			)
		)
		(duplicate_pad_numbers_are_jumpers no)
		(fp_line
			(start -0.7874 0.4064)
			(end -0.7874 -0.4064)
			(stroke
				(width 0.1524)
				(type default)
			)
			(layer "F.SilkS")
		)
		(fp_line
			(start 0.7874 0.4064)
			(end -0.7874 0.4064)
			(stroke
				(width 0.1524)
				(type default)
			)
			(layer "F.SilkS")
		)
		(fp_line
			(start -0.7874 -0.4064)
			(end 0.7874 -0.4064)
			(stroke
				(width 0.1524)
				(type default)
			)
			(layer "F.SilkS")
		)
		(fp_line
			(start 0.7874 -0.4064)
			(end 0.7874 0.4064)
			(stroke
				(width 0.1524)
				(type default)
			)
			(layer "F.SilkS")
		)
		(fp_line
			(start -0.67945 0.3048)
			(end -0.67945 -0.305054)
			(stroke
				(width 0.1)
				(type default)
			)
			(layer "F.Fab")
		)
		(fp_line
			(start -0.12065 0.3048)
			(end -0.67945 0.3048)
			(stroke
				(width 0.1)
				(type default)
			)
			(layer "F.Fab")
		)
		(fp_line
			(start 0.120396 0.3048)
			(end 0.120396 0.2794)
			(stroke
				(width 0.1)
				(type default)
			)
			(layer "F.Fab")
		)
		(fp_line
			(start 0.67945 0.3048)
			(end 0.120396 0.3048)
			(stroke
				(width 0.1)
				(type default)
			)
			(layer "F.Fab")
		)
		(fp_line
			(start -0.12065 0.2794)
			(end -0.12065 0.3048)
			(stroke
				(width 0.1)
				(type default)
			)
			(layer "F.Fab")
		)
		(fp_line
			(start 0.120396 0.2794)
			(end -0.12065 0.2794)
			(stroke
				(width 0.1)
				(type default)
			)
			(layer "F.Fab")
		)
		(fp_line
			(start -0.12065 -0.2794)
			(end 0.12065 -0.2794)
			(stroke
				(width 0.1)
				(type default)
			)
			(layer "F.Fab")
		)
		(fp_line
			(start 0.12065 -0.2794)
			(end 0.12065 -0.3048)
			(stroke
				(width 0.1)
				(type default)
			)
			(layer "F.Fab")
		)
		(fp_line
			(start 0.12065 -0.3048)
			(end 0.67945 -0.3048)
			(stroke
				(width 0.1)
				(type default)
			)
			(layer "F.Fab")
		)
		(fp_line
			(start 0.67945 -0.3048)
			(end 0.67945 0.3048)
			(stroke
				(width 0.1)
				(type default)
			)
			(layer "F.Fab")
		)
		(fp_line
			(start -0.67945 -0.305054)
			(end -0.12065 -0.305054)
			(stroke
				(width 0.1)
				(type default)
			)
			(layer "F.Fab")
		)
		(fp_line
			(start -0.12065 -0.305054)
			(end -0.12065 -0.2794)
			(stroke
				(width 0.1)
				(type default)
			)
			(layer "F.Fab")
		)
		(pad "1" smd circle
			(at -0.40005 0 270)
			(size 0 0)
			(layers "F.Cu" "F.Mask" "F.Paste")
			(net "PVCCFA_EHV_FIVRA_CPU0")
		)
		(pad "2" smd circle
			(at 0.40005 0 270)
			(size 0 0)
			(layers "F.Cu" "F.Mask" "F.Paste")
			(net "GND")
		)
	)
	(footprint ""
		(layer "F.Cu")
		(at 419.731698 -362.155994 -90)
		(property "Reference" "PC604_P0_1"
			(at 0 0 270)
			(layer "F.SilkS")
			(hide yes)
			(effects
				(font
					(size 1.27 1.27)
				)
			)
		)
		(property "Value" ""
			(at 0 0 270)
			(layer "F.Fab")
			(effects
				(font
					(size 1.27 1.27)
				)
			)
		)
		(duplicate_pad_numbers_are_jumpers no)
		(fp_line
			(start -0.7874 0.4064)
			(end -0.7874 -0.4064)
			(stroke
				(width 0.1524)
				(type default)
			)
			(layer "F.SilkS")
		)
		(fp_line
			(start 0.7874 0.4064)
			(end -0.7874 0.4064)
			(stroke
				(width 0.1524)
				(type default)
			)
			(layer "F.SilkS")
		)
		(fp_line
			(start -0.7874 -0.4064)
			(end 0.7874 -0.4064)
			(stroke
				(width 0.1524)
				(type default)
			)
			(layer "F.SilkS")
		)
		(fp_line
			(start 0.7874 -0.4064)
			(end 0.7874 0.4064)
			(stroke
				(width 0.1524)
				(type default)
			)
			(layer "F.SilkS")
		)
		(fp_line
			(start -0.67945 0.3048)
			(end -0.67945 -0.305054)
			(stroke
				(width 0.1)
				(type default)
			)
			(layer "F.Fab")
		)
		(fp_line
			(start -0.12065 0.3048)
			(end -0.67945 0.3048)
			(stroke
				(width 0.1)
				(type default)
			)
			(layer "F.Fab")
		)
		(fp_line
			(start 0.120396 0.3048)
			(end 0.120396 0.2794)
			(stroke
				(width 0.1)
				(type default)
			)
			(layer "F.Fab")
		)
		(fp_line
			(start 0.67945 0.3048)
			(end 0.120396 0.3048)
			(stroke
				(width 0.1)
				(type default)
			)
			(layer "F.Fab")
		)
		(fp_line
			(start -0.12065 0.2794)
			(end -0.12065 0.3048)
			(stroke
				(width 0.1)
				(type default)
			)
			(layer "F.Fab")
		)
		(fp_line
			(start 0.120396 0.2794)
			(end -0.12065 0.2794)
			(stroke
				(width 0.1)
				(type default)
			)
			(layer "F.Fab")
		)
		(fp_line
			(start -0.12065 -0.2794)
			(end 0.12065 -0.2794)
			(stroke
				(width 0.1)
				(type default)
			)
			(layer "F.Fab")
		)
		(fp_line
			(start 0.12065 -0.2794)
			(end 0.12065 -0.3048)
			(stroke
				(width 0.1)
				(type default)
			)
			(layer "F.Fab")
		)
		(fp_line
			(start 0.12065 -0.3048)
			(end 0.67945 -0.3048)
			(stroke
				(width 0.1)
				(type default)
			)
			(layer "F.Fab")
		)
		(fp_line
			(start 0.67945 -0.3048)
			(end 0.67945 0.3048)
			(stroke
				(width 0.1)
				(type default)
			)
			(layer "F.Fab")
		)
		(fp_line
			(start -0.67945 -0.305054)
			(end -0.12065 -0.305054)
			(stroke
				(width 0.1)
				(type default)
			)
			(layer "F.Fab")
		)
		(fp_line
			(start -0.12065 -0.305054)
			(end -0.12065 -0.2794)
			(stroke
				(width 0.1)
				(type default)
			)
			(layer "F.Fab")
		)
		(pad "1" smd circle
			(at -0.40005 0 270)
			(size 0 0)
			(layers "F.Cu" "F.Mask" "F.Paste")
			(net "SW_P12V_PVCCFA_EHV_FIVRA_CPU0_R")
		)
		(pad "2" smd circle
			(at 0.40005 0 270)
			(size 0 0)
			(layers "F.Cu" "F.Mask" "F.Paste")
			(net "GND")
		)
	)
	(footprint ""
		(layer "F.Cu")
		(at 21.801582 -423.629836 -90)
		(property "Reference" "R3067"
			(at 0 0 270)
			(layer "F.SilkS")
			(hide yes)
			(effects
				(font
					(size 1.27 1.27)
				)
			)
		)
		(property "Value" ""
			(at 0 0 270)
			(layer "F.Fab")
			(effects
				(font
					(size 1.27 1.27)
				)
			)
		)
		(duplicate_pad_numbers_are_jumpers no)
		(fp_line
			(start -0.7874 0.4064)
			(end -0.7874 -0.4064)
			(stroke
				(width 0.1524)
				(type default)
			)
			(layer "F.SilkS")
		)
		(fp_line
			(start 0.7874 0.4064)
			(end -0.7874 0.4064)
			(stroke
				(width 0.1524)
				(type default)
			)
			(layer "F.SilkS")
		)
		(fp_line
			(start -0.7874 -0.4064)
			(end 0.7874 -0.4064)
			(stroke
				(width 0.1524)
				(type default)
			)
			(layer "F.SilkS")
		)
		(fp_line
			(start 0.7874 -0.4064)
			(end 0.7874 0.4064)
			(stroke
				(width 0.1524)
				(type default)
			)
			(layer "F.SilkS")
		)
		(fp_line
			(start -0.67945 0.3048)
			(end -0.67945 -0.305054)
			(stroke
				(width 0.1)
				(type default)
			)
			(layer "F.Fab")
		)
		(fp_line
			(start -0.12065 0.3048)
			(end -0.67945 0.3048)
			(stroke
				(width 0.1)
				(type default)
			)
			(layer "F.Fab")
		)
		(fp_line
			(start 0.120396 0.3048)
			(end 0.120396 0.2794)
			(stroke
				(width 0.1)
				(type default)
			)
			(layer "F.Fab")
		)
		(fp_line
			(start 0.67945 0.3048)
			(end 0.120396 0.3048)
			(stroke
				(width 0.1)
				(type default)
			)
			(layer "F.Fab")
		)
		(fp_line
			(start -0.12065 0.2794)
			(end -0.12065 0.3048)
			(stroke
				(width 0.1)
				(type default)
			)
			(layer "F.Fab")
		)
		(fp_line
			(start 0.120396 0.2794)
			(end -0.12065 0.2794)
			(stroke
				(width 0.1)
				(type default)
			)
			(layer "F.Fab")
		)
		(fp_line
			(start -0.12065 -0.2794)
			(end 0.12065 -0.2794)
			(stroke
				(width 0.1)
				(type default)
			)
			(layer "F.Fab")
		)
		(fp_line
			(start 0.12065 -0.2794)
			(end 0.12065 -0.3048)
			(stroke
				(width 0.1)
				(type default)
			)
			(layer "F.Fab")
		)
		(fp_line
			(start 0.12065 -0.3048)
			(end 0.67945 -0.3048)
			(stroke
				(width 0.1)
				(type default)
			)
			(layer "F.Fab")
		)
		(fp_line
			(start 0.67945 -0.3048)
			(end 0.67945 0.3048)
			(stroke
				(width 0.1)
				(type default)
			)
			(layer "F.Fab")
		)
		(fp_line
			(start -0.67945 -0.305054)
			(end -0.12065 -0.305054)
			(stroke
				(width 0.1)
				(type default)
			)
			(layer "F.Fab")
		)
		(fp_line
			(start -0.12065 -0.305054)
			(end -0.12065 -0.2794)
			(stroke
				(width 0.1)
				(type default)
			)
			(layer "F.Fab")
		)
		(pad "1" smd circle
			(at -0.40005 0 270)
			(size 0 0)
			(layers "F.Cu" "F.Mask" "F.Paste")
			(net "FM_SMB_2_ALERT_GPU_ISO_N")
		)
		(pad "2" smd circle
			(at 0.40005 0 270)
			(size 0 0)
			(layers "F.Cu" "F.Mask" "F.Paste")
			(net "FM_SMB_2_ALERT_GPU_ISO_R_N")
		)
	)
)
